# SCM (Grand Teton) — schematic netlist excerpt (pin names and nets, part order shuffled) for the footprints in the layout excerpt that follows; sources: Cadence DE-HDL packaged netlist, KiCad conversion of 12092022_DA0F0TMDCD0_F0T_Management_Board_D_brd_V3_OCP.brd

U33  74HC1G126GW  IC  pkg TSSOP5_0-65_2-05X1-25  page 23
  \1\  = BMC_DDC_BUF_EN
  \2\  = V_VGAHS
  GND  = GND
  \4\  = V_VGAHS_BUF_R
  \5\  = BMC_DDC_BUF_PWR

R208  Q_RES  0 5% EMPTY  pkg 0402LF  page 15 : A = P1V8_AUX ; B = P3V3_P1V8_SD1VDD

(kicad_pcb
	(version 20260206)
	(generator "pcbnew")
	(generator_version "10.0")
	(general
		(thickness 1.6)
		(legacy_teardrops no)
	)
	(paper "A4")
	(title_block
		(title "12092022_DA0F0TMDCD0_F0T_Management_Board_D_brd_V3_OCP.brd")
		(comment 1 "Grand Teton / footprints 1272-1273 of 1440")
	)
	(layers
		(0 "F.Cu" signal "TOP")
		(4 "In1.Cu" signal "GND")
		(6 "In2.Cu" signal "IN1")
		(8 "In3.Cu" signal "GND1")
		(10 "In4.Cu" signal "IN2")
		(12 "In5.Cu" signal "VCC")
		(14 "In6.Cu" signal "VCC1")
		(16 "In7.Cu" signal "IN3")
		(18 "In8.Cu" signal "GND2")
		(20 "In9.Cu" signal "IN4")
		(22 "In10.Cu" signal "GND3")
		(2 "B.Cu" signal "BOTTOM")
		(9 "F.Adhes" user "F.Adhesive")
		(11 "B.Adhes" user "B.Adhesive")
		(13 "F.Paste" user "Package Geometry/Pastemask Top")
		(15 "B.Paste" user "Package Geometry/Pastemask Bottom")
		(5 "F.SilkS" user "Ref Des/Silkscreen Top")
		(7 "B.SilkS" user "Ref Des/Silkscreen Bottom")
		(1 "F.Mask" user "Board Geometry/Soldermask Top")
		(3 "B.Mask" user "Board Geometry/Soldermask Bottom")
		(17 "Dwgs.User" user "User.Drawings")
		(19 "Cmts.User" user "User.Comments")
		(21 "Eco1.User" user "User.Eco1")
		(23 "Eco2.User" user "User.Eco2")
		(25 "Edge.Cuts" user "Board Geometry/Outline")
		(27 "Margin" user)
		(31 "F.CrtYd" user "Package Geometry/Place Bound Top")
		(29 "B.CrtYd" user "Package Geometry/Place Bound Bottom")
		(35 "F.Fab" user "Ref Des/Assembly Top")
		(33 "B.Fab" user "Ref Des/Assembly Bottom")
	)
	(footprint ""
		(layer "B.Cu")
		(at 38.3286 -4.1148 -90)
		(property "Reference" "U33"
			(at 0.924052 1.4986 0)
			(unlocked yes)
			(layer "B.SilkS")
			(effects
				(font
					(size 0.7874 0.5842)
					(thickness 0.1524)
				)
				(justify left mirror)
			)
		)
		(property "Value" ""
			(at 0 0 90)
			(layer "B.Fab")
			(effects
				(font
					(size 1.27 1.27)
				)
				(justify mirror)
			)
		)
		(duplicate_pad_numbers_are_jumpers no)
		(fp_line
			(start -1.3462 1.1938)
			(end -1.3462 -1.1938)
			(stroke
				(width 0.1524)
				(type default)
			)
			(layer "B.SilkS")
		)
		(fp_line
			(start 1.3462 1.1938)
			(end -1.3462 1.1938)
			(stroke
				(width 0.1524)
				(type default)
			)
			(layer "B.SilkS")
		)
		(fp_line
			(start -1.3462 -1.1938)
			(end 1.3462 -1.1938)
			(stroke
				(width 0.1524)
				(type default)
			)
			(layer "B.SilkS")
		)
		(fp_line
			(start 1.3462 -1.1938)
			(end 1.3462 1.1684)
			(stroke
				(width 0.1524)
				(type default)
			)
			(layer "B.SilkS")
		)
		(fp_poly
			(pts
				(xy 1.447038 -0.760476) (xy 2.052066 -0.457962) (xy 2.052066 -1.06299)
			)
			(stroke
				(width 0)
				(type default)
			)
			(fill yes)
			(layer "B.SilkS")
		)
		(fp_line
			(start -0.674878 1.124966)
			(end -0.674878 -1.124966)
			(stroke
				(width 0.1)
				(type default)
			)
			(layer "B.Fab")
		)
		(fp_line
			(start 0.674878 1.124966)
			(end -0.674878 1.124966)
			(stroke
				(width 0.1)
				(type default)
			)
			(layer "B.Fab")
		)
		(fp_line
			(start -0.674878 -1.124966)
			(end 0.674878 -1.124966)
			(stroke
				(width 0.1)
				(type default)
			)
			(layer "B.Fab")
		)
		(fp_line
			(start 0.674878 -1.124966)
			(end 0.674878 1.124966)
			(stroke
				(width 0.1)
				(type default)
			)
			(layer "B.Fab")
		)
		(fp_poly
			(pts
				(xy 1.447038 -0.760476) (xy 2.052066 -0.457962) (xy 2.052066 -1.06299)
			)
			(stroke
				(width 0)
				(type default)
			)
			(fill yes)
			(layer "B.Fab")
		)
		(pad "1" smd rect
			(at 0.899922 -0.750062 90)
			(size 0.6096 0.6096)
			(layers "B.Cu" "B.Mask" "B.Paste")
			(net "BMC_DDC_BUF_EN")
		)
		(pad "2" smd rect
			(at 0.899922 0)
			(size 0.4064 0.6096)
			(layers "B.Cu" "B.Mask" "B.Paste")
			(net "V_VGAHS")
		)
		(pad "3" smd rect
			(at 0.899922 0.750062 90)
			(size 0.6096 0.6096)
			(layers "B.Cu" "B.Mask" "B.Paste")
			(net "GND")
		)
		(pad "4" smd rect
			(at -0.899922 0.750062 90)
			(size 0.6096 0.6096)
			(layers "B.Cu" "B.Mask" "B.Paste")
			(net "V_VGAHS_BUF_R")
		)
		(pad "5" smd rect
			(at -0.899922 -0.750062 90)
			(size 0.6096 0.6096)
			(layers "B.Cu" "B.Mask" "B.Paste")
			(net "BMC_DDC_BUF_PWR")
		)
	)
	(footprint ""
		(layer "B.Cu")
		(at 38.47084 -35.828224)
		(property "Reference" "R208"
			(at 0 0 0)
			(layer "B.SilkS")
			(hide yes)
			(effects
				(font
					(size 1.27 1.27)
				)
				(justify mirror)
			)
		)
		(property "Value" ""
			(at 0 0 0)
			(layer "B.Fab")
			(effects
				(font
					(size 1.27 1.27)
				)
				(justify mirror)
			)
		)
		(duplicate_pad_numbers_are_jumpers no)
		(fp_line
			(start -0.7874 -0.4064)
			(end -0.7874 0.4064)
			(stroke
				(width 0.1524)
				(type default)
			)
			(layer "B.SilkS")
		)
		(fp_line
			(start -0.7874 0.4064)
			(end 0.7874 0.4064)
			(stroke
				(width 0.1524)
				(type default)
			)
			(layer "B.SilkS")
		)
		(fp_line
			(start 0.7874 -0.4064)
			(end -0.7874 -0.4064)
			(stroke
				(width 0.1524)
				(type default)
			)
			(layer "B.SilkS")
		)
		(fp_line
			(start 0.7874 0.4064)
			(end 0.7874 -0.4064)
			(stroke
				(width 0.1524)
				(type default)
			)
			(layer "B.SilkS")
		)
		(fp_line
			(start -0.67945 -0.3048)
			(end -0.67945 0.3048)
			(stroke
				(width 0.1)
				(type default)
			)
			(layer "B.Fab")
		)
		(fp_line
			(start -0.67945 0.3048)
			(end -0.120396 0.3048)
			(stroke
				(width 0.1)
				(type default)
			)
			(layer "B.Fab")
		)
		(fp_line
			(start -0.12065 -0.3048)
			(end -0.67945 -0.3048)
			(stroke
				(width 0.1)
				(type default)
			)
			(layer "B.Fab")
		)
		(fp_line
			(start -0.12065 -0.2794)
			(end -0.12065 -0.3048)
			(stroke
				(width 0.1)
				(type default)
			)
			(layer "B.Fab")
		)
		(fp_line
			(start -0.120396 0.2794)
			(end 0.12065 0.2794)
			(stroke
				(width 0.1)
				(type default)
			)
			(layer "B.Fab")
		)
		(fp_line
			(start -0.120396 0.3048)
			(end -0.120396 0.2794)
			(stroke
				(width 0.1)
				(type default)
			)
			(layer "B.Fab")
		)
		(fp_line
			(start 0.12065 -0.305054)
			(end 0.12065 -0.2794)
			(stroke
				(width 0.1)
				(type default)
			)
			(layer "B.Fab")
		)
		(fp_line
			(start 0.12065 -0.2794)
			(end -0.12065 -0.2794)
			(stroke
				(width 0.1)
				(type default)
			)
			(layer "B.Fab")
		)
		(fp_line
			(start 0.12065 0.2794)
			(end 0.12065 0.3048)
			(stroke
				(width 0.1)
				(type default)
			)
			(layer "B.Fab")
		)
		(fp_line
			(start 0.12065 0.3048)
			(end 0.67945 0.3048)
			(stroke
				(width 0.1)
				(type default)
			)
			(layer "B.Fab")
		)
		(fp_line
			(start 0.67945 -0.305054)
			(end 0.12065 -0.305054)
			(stroke
				(width 0.1)
				(type default)
			)
			(layer "B.Fab")
		)
		(fp_line
			(start 0.67945 0.3048)
			(end 0.67945 -0.305054)
			(stroke
				(width 0.1)
				(type default)
			)
			(layer "B.Fab")
		)
		(pad "1" smd circle
			(at 0.40005 0 180)
			(size 0 0)
			(layers "B.Cu" "B.Mask" "B.Paste")
			(net "P1V8_AUX")
		)
		(pad "2" smd circle
			(at -0.40005 0 180)
			(size 0 0)
			(layers "B.Cu" "B.Mask" "B.Paste")
			(net "P3V3_P1V8_SD1VDD")
		)
	)
)
